(kicad_pcb
	(version 20260206)
	(generator "pcbnew")
	(generator_version "10.0")
	(general
		(thickness 1.6)
		(legacy_teardrops no)
	)
	(paper "A4")
	(title_block
		(title "04192023_DAF0TMB3IC0_F0TG_MB_C_brd_V02_OCP.brd")
		(comment 1 "Grand Teton / footprint 2783 of 8354 (U26), pads 5780-5888 of 6102")
	)
	(layers
		(0 "F.Cu" signal "TOP")
		(4 "In1.Cu" signal "GND")
		(6 "In2.Cu" signal "IN1")
		(8 "In3.Cu" signal "GND1")
		(10 "In4.Cu" signal "IN2")
		(12 "In5.Cu" signal "GND2")
		(14 "In6.Cu" signal "IN3")
		(16 "In7.Cu" signal "GND3")
		(18 "In8.Cu" signal "VCC")
		(20 "In9.Cu" signal "VCC1")
		(22 "In10.Cu" signal "GND4")
		(24 "In11.Cu" signal "IN4")
		(26 "In12.Cu" signal "GND5")
		(28 "In13.Cu" signal "IN5")
		(30 "In14.Cu" signal "GND6")
		(32 "In15.Cu" signal "IN6")
		(34 "In16.Cu" signal "GND7")
		(2 "B.Cu" signal "BOTTOM")
		(9 "F.Adhes" user "F.Adhesive")
		(11 "B.Adhes" user "B.Adhesive")
		(13 "F.Paste" user "Package Geometry/Pastemask Top")
		(15 "B.Paste" user "Package Geometry/Pastemask Bottom")
		(5 "F.SilkS" user "Ref Des/Silkscreen Top")
		(7 "B.SilkS" user "Ref Des/Silkscreen Bottom")
		(1 "F.Mask" user "Board Geometry/Soldermask Top")
		(3 "B.Mask" user "Board Geometry/Soldermask Bottom")
		(17 "Dwgs.User" user "User.Drawings")
		(19 "Cmts.User" user "User.Comments")
		(21 "Eco1.User" user "User.Eco1")
		(23 "Eco2.User" user "User.Eco2")
		(25 "Edge.Cuts" user "Board Geometry/Outline")
		(27 "Margin" user)
		(31 "F.CrtYd" user "Package Geometry/Place Bound Top")
		(29 "B.CrtYd" user "Package Geometry/Place Bound Bottom")
		(35 "F.Fab" user "Ref Des/Assembly Top")
		(33 "B.Fab" user "Ref Des/Assembly Bottom")
	)
	(footprint ""
		(layer "F.Cu")
		(at 111.927894 -258.880356 180)
		(property "Reference" "U26"
			(at -45.05579 -61.794136 0)
			(unlocked yes)
			(layer "F.SilkS")
			(effects
				(font
					(size 0.7874 0.5842)
					(thickness 0.1524)
				)
			)
		)
		(property "Value" ""
			(at 0 0 180)
			(layer "F.Fab")
			(effects
				(font
					(size 1.27 1.27)
				)
			)
		)
		(duplicate_pad_numbers_are_jumpers no)
		(pad "T40" smd circle
			(at 2.029968 -24.660098 180)
			(size 0.450088 0.450088)
			(layers "F.Cu" "F.Mask" "F.Paste")
			(net "P5E_CPU1_G1_RX_DN<1>")
		)
		(pad "T41" smd circle
			(at 2.970022 -24.660098 180)
			(size 0.450088 0.450088)
			(layers "F.Cu" "F.Mask" "F.Paste")
			(net "P5E_CPU1_G1_RX_DP<1>")
		)
		(pad "T42" smd circle
			(at 3.910076 -24.660098 180)
			(size 0.450088 0.450088)
			(layers "F.Cu" "F.Mask" "F.Paste")
			(net "GND")
		)
		(pad "T43" smd circle
			(at 4.849876 -24.660098 180)
			(size 0.450088 0.450088)
			(layers "F.Cu" "F.Mask" "F.Paste")
			(net "PVDDCR_CPU0_P1")
		)
		(pad "T44" smd circle
			(at 5.78993 -24.660098 180)
			(size 0.450088 0.450088)
			(layers "F.Cu" "F.Mask" "F.Paste")
			(net "PVDDCR_CPU0_P1")
		)
		(pad "T45" smd circle
			(at 6.729984 -24.660098 180)
			(size 0.450088 0.450088)
			(layers "F.Cu" "F.Mask" "F.Paste")
			(net "GND")
		)
		(pad "T46" smd circle
			(at 7.670038 -24.660098 180)
			(size 0.450088 0.450088)
			(layers "F.Cu" "F.Mask" "F.Paste")
			(net "PVDDCR_CPU0_P1")
		)
		(pad "T47" smd circle
			(at 8.610092 -24.660098 180)
			(size 0.450088 0.450088)
			(layers "F.Cu" "F.Mask" "F.Paste")
			(net "PVDDCR_CPU0_P1")
		)
		(pad "T48" smd circle
			(at 9.549892 -24.660098 180)
			(size 0.450088 0.450088)
			(layers "F.Cu" "F.Mask" "F.Paste")
			(net "GND")
		)
		(pad "T49" smd circle
			(at 10.489946 -24.660098 180)
			(size 0.450088 0.450088)
			(layers "F.Cu" "F.Mask" "F.Paste")
			(net "PVDDCR_CPU0_P1")
		)
		(pad "T50" smd circle
			(at 11.43 -24.660098 180)
			(size 0.450088 0.450088)
			(layers "F.Cu" "F.Mask" "F.Paste")
			(net "PVDDCR_CPU0_P1")
		)
		(pad "T51" smd circle
			(at 12.370054 -24.660098 180)
			(size 0.450088 0.450088)
			(layers "F.Cu" "F.Mask" "F.Paste")
			(net "GND")
		)
		(pad "T52" smd circle
			(at 13.310108 -24.660098 180)
			(size 0.450088 0.450088)
			(layers "F.Cu" "F.Mask" "F.Paste")
			(net "PVDDCR_CPU0_P1")
		)
		(pad "T53" smd circle
			(at 14.249908 -24.660098 180)
			(size 0.450088 0.450088)
			(layers "F.Cu" "F.Mask" "F.Paste")
			(net "PVDDCR_CPU0_P1")
		)
		(pad "T54" smd circle
			(at 15.189962 -24.660098 180)
			(size 0.450088 0.450088)
			(layers "F.Cu" "F.Mask" "F.Paste")
			(net "GND")
		)
		(pad "T55" smd circle
			(at 16.130016 -24.660098 180)
			(size 0.450088 0.450088)
			(layers "F.Cu" "F.Mask" "F.Paste")
			(net "M_C_CPU1_SA_DQ<13>")
		)
		(pad "T56" smd circle
			(at 17.07007 -24.660098 180)
			(size 0.450088 0.450088)
			(layers "F.Cu" "F.Mask" "F.Paste")
			(net "M_C_CPU1_SA_DQ<14>")
		)
		(pad "T57" smd circle
			(at 18.010124 -24.660098 180)
			(size 0.450088 0.450088)
			(layers "F.Cu" "F.Mask" "F.Paste")
			(net "GND")
		)
		(pad "T58" smd circle
			(at 18.949924 -24.660098 180)
			(size 0.450088 0.450088)
			(layers "F.Cu" "F.Mask" "F.Paste")
			(net "M_D_CPU1_SA_DQ<13>")
		)
		(pad "T59" smd circle
			(at 19.889978 -24.660098 180)
			(size 0.450088 0.450088)
			(layers "F.Cu" "F.Mask" "F.Paste")
			(net "GND")
		)
		(pad "T60" smd circle
			(at 20.830032 -24.660098 180)
			(size 0.450088 0.450088)
			(layers "F.Cu" "F.Mask" "F.Paste")
			(net "M_D_CPU1_SA_DQ<14>")
		)
		(pad "T61" smd circle
			(at 21.770086 -24.660098 180)
			(size 0.450088 0.450088)
			(layers "F.Cu" "F.Mask" "F.Paste")
			(net "GND")
		)
		(pad "T62" smd circle
			(at 22.709886 -24.660098 180)
			(size 0.450088 0.450088)
			(layers "F.Cu" "F.Mask" "F.Paste")
			(net "M_B_CPU1_SA_DQ<13>")
		)
		(pad "T63" smd circle
			(at 23.64994 -24.660098 180)
			(size 0.450088 0.450088)
			(layers "F.Cu" "F.Mask" "F.Paste")
			(net "M_B_CPU1_SA_DQ<14>")
		)
		(pad "T64" smd circle
			(at 24.589994 -24.660098 180)
			(size 0.450088 0.450088)
			(layers "F.Cu" "F.Mask" "F.Paste")
			(net "GND")
		)
		(pad "T65" smd circle
			(at 25.530048 -24.660098 180)
			(size 0.450088 0.450088)
			(layers "F.Cu" "F.Mask" "F.Paste")
			(net "M_F_CPU1_SA_DQ<13>")
		)
		(pad "T66" smd circle
			(at 26.470102 -24.660098 180)
			(size 0.450088 0.450088)
			(layers "F.Cu" "F.Mask" "F.Paste")
			(net "GND")
		)
		(pad "T67" smd circle
			(at 27.409902 -24.660098 180)
			(size 0.450088 0.450088)
			(layers "F.Cu" "F.Mask" "F.Paste")
			(net "M_F_CPU1_SA_DQ<14>")
		)
		(pad "T68" smd circle
			(at 28.349956 -24.660098 180)
			(size 0.450088 0.450088)
			(layers "F.Cu" "F.Mask" "F.Paste")
			(net "GND")
		)
		(pad "T69" smd circle
			(at 29.29001 -24.660098 180)
			(size 0.450088 0.450088)
			(layers "F.Cu" "F.Mask" "F.Paste")
			(net "M_E_CPU1_SA_DQ<13>")
		)
		(pad "T70" smd circle
			(at 30.230064 -24.660098 180)
			(size 0.450088 0.450088)
			(layers "F.Cu" "F.Mask" "F.Paste")
			(net "M_E_CPU1_SA_DQ<14>")
		)
		(pad "T71" smd circle
			(at 31.170118 -24.660098 180)
			(size 0.450088 0.450088)
			(layers "F.Cu" "F.Mask" "F.Paste")
			(net "GND")
		)
		(pad "T72" smd circle
			(at 32.109918 -24.660098 180)
			(size 0.450088 0.450088)
			(layers "F.Cu" "F.Mask" "F.Paste")
			(net "M_A_CPU1_SA_DQ<13>")
		)
		(pad "T73" smd circle
			(at 33.049972 -24.660098 180)
			(size 0.450088 0.450088)
			(layers "F.Cu" "F.Mask" "F.Paste")
			(net "GND")
		)
		(pad "T74" smd circle
			(at 33.990026 -24.660098 180)
			(size 0.450088 0.450088)
			(layers "F.Cu" "F.Mask" "F.Paste")
			(net "M_A_CPU1_SA_DQ<14>")
		)
		(pad "U1" smd circle
			(at -34.159952 -23.850092 180)
			(size 0.450088 0.450088)
			(layers "F.Cu" "F.Mask" "F.Paste")
			(net "GND")
		)
		(pad "U2" smd circle
			(at -33.219898 -23.850092 180)
			(size 0.450088 0.450088)
			(layers "F.Cu" "F.Mask" "F.Paste")
			(net "M_G_CPU1_SA_DQ<16>")
		)
		(pad "U3" smd circle
			(at -32.280098 -23.850092 180)
			(size 0.450088 0.450088)
			(layers "F.Cu" "F.Mask" "F.Paste")
			(net "M_G_CPU1_SA_DQ<15>")
		)
		(pad "U4" smd circle
			(at -31.340044 -23.850092 180)
			(size 0.450088 0.450088)
			(layers "F.Cu" "F.Mask" "F.Paste")
			(net "PVDDCR_SOC_P1")
		)
		(pad "U5" smd circle
			(at -30.39999 -23.850092 180)
			(size 0.450088 0.450088)
			(layers "F.Cu" "F.Mask" "F.Paste")
			(net "M_K_CPU1_SA_DQ<16>")
		)
		(pad "U6" smd circle
			(at -29.459936 -23.850092 180)
			(size 0.450088 0.450088)
			(layers "F.Cu" "F.Mask" "F.Paste")
			(net "GND")
		)
		(pad "U7" smd circle
			(at -28.519882 -23.850092 180)
			(size 0.450088 0.450088)
			(layers "F.Cu" "F.Mask" "F.Paste")
			(net "M_K_CPU1_SA_DQ<15>")
		)
		(pad "U8" smd circle
			(at -27.580082 -23.850092 180)
			(size 0.450088 0.450088)
			(layers "F.Cu" "F.Mask" "F.Paste")
			(net "GND")
		)
		(pad "U9" smd circle
			(at -26.640028 -23.850092 180)
			(size 0.450088 0.450088)
			(layers "F.Cu" "F.Mask" "F.Paste")
			(net "M_L_CPU1_SA_DQ<16>")
		)
		(pad "U10" smd circle
			(at -25.699974 -23.850092 180)
			(size 0.450088 0.450088)
			(layers "F.Cu" "F.Mask" "F.Paste")
			(net "M_L_CPU1_SA_DQ<15>")
		)
		(pad "U11" smd circle
			(at -24.75992 -23.850092 180)
			(size 0.450088 0.450088)
			(layers "F.Cu" "F.Mask" "F.Paste")
			(net "PVDDCR_SOC_P1")
		)
		(pad "U12" smd circle
			(at -23.82012 -23.850092 180)
			(size 0.450088 0.450088)
			(layers "F.Cu" "F.Mask" "F.Paste")
			(net "M_H_CPU1_SA_DQ<16>")
		)
		(pad "U13" smd circle
			(at -22.880066 -23.850092 180)
			(size 0.450088 0.450088)
			(layers "F.Cu" "F.Mask" "F.Paste")
			(net "GND")
		)
		(pad "U14" smd circle
			(at -21.940012 -23.850092 180)
			(size 0.450088 0.450088)
			(layers "F.Cu" "F.Mask" "F.Paste")
			(net "M_H_CPU1_SA_DQ<15>")
		)
		(pad "U15" smd circle
			(at -20.999958 -23.850092 180)
			(size 0.450088 0.450088)
			(layers "F.Cu" "F.Mask" "F.Paste")
			(net "GND")
		)
		(pad "U16" smd circle
			(at -20.059904 -23.850092 180)
			(size 0.450088 0.450088)
			(layers "F.Cu" "F.Mask" "F.Paste")
			(net "M_J_CPU1_SA_DQ<16>")
		)
		(pad "U17" smd circle
			(at -19.120104 -23.850092 180)
			(size 0.450088 0.450088)
			(layers "F.Cu" "F.Mask" "F.Paste")
			(net "M_J_CPU1_SA_DQ<15>")
		)
		(pad "U18" smd circle
			(at -18.18005 -23.850092 180)
			(size 0.450088 0.450088)
			(layers "F.Cu" "F.Mask" "F.Paste")
			(net "PVDDCR_SOC_P1")
		)
		(pad "U19" smd circle
			(at -17.239996 -23.850092 180)
			(size 0.450088 0.450088)
			(layers "F.Cu" "F.Mask" "F.Paste")
			(net "M_I_CPU1_SA_DQ<16>")
		)
		(pad "U20" smd circle
			(at -16.299942 -23.850092 180)
			(size 0.450088 0.450088)
			(layers "F.Cu" "F.Mask" "F.Paste")
			(net "GND")
		)
		(pad "U21" smd circle
			(at -15.359888 -23.850092 180)
			(size 0.450088 0.450088)
			(layers "F.Cu" "F.Mask" "F.Paste")
			(net "M_I_CPU1_SA_DQ<15>")
		)
		(pad "U22" smd circle
			(at -14.420088 -23.850092 180)
			(size 0.450088 0.450088)
			(layers "F.Cu" "F.Mask" "F.Paste")
			(net "GND")
		)
		(pad "U23" smd circle
			(at -13.480034 -23.850092 180)
			(size 0.450088 0.450088)
			(layers "F.Cu" "F.Mask" "F.Paste")
			(net "GMI_CPU1_G3_CPU0_G1_TX_DP<15>")
		)
		(pad "U24" smd circle
			(at -12.53998 -23.850092 180)
			(size 0.450088 0.450088)
			(layers "F.Cu" "F.Mask" "F.Paste")
			(net "GMI_CPU1_G3_CPU0_G1_TX_DN<15>")
		)
		(pad "U25" smd circle
			(at -11.599926 -23.850092 180)
			(size 0.450088 0.450088)
			(layers "F.Cu" "F.Mask" "F.Paste")
			(net "GND")
		)
		(pad "U26" smd circle
			(at -10.659872 -23.850092 180)
			(size 0.450088 0.450088)
			(layers "F.Cu" "F.Mask" "F.Paste")
			(net "GMI_CPU1_G3_CPU0_G1_TX_DP<12>")
		)
		(pad "U27" smd circle
			(at -9.720072 -23.850092 180)
			(size 0.450088 0.450088)
			(layers "F.Cu" "F.Mask" "F.Paste")
			(net "GMI_CPU1_G3_CPU0_G1_TX_DN<12>")
		)
		(pad "U28" smd circle
			(at -8.780018 -23.850092 180)
			(size 0.450088 0.450088)
			(layers "F.Cu" "F.Mask" "F.Paste")
			(net "GND")
		)
		(pad "U29" smd circle
			(at -7.839964 -23.850092 180)
			(size 0.450088 0.450088)
			(layers "F.Cu" "F.Mask" "F.Paste")
			(net "GMI_CPU1_G3_CPU0_G1_TX_DP<6>")
		)
		(pad "U30" smd circle
			(at -6.89991 -23.850092 180)
			(size 0.450088 0.450088)
			(layers "F.Cu" "F.Mask" "F.Paste")
			(net "GMI_CPU1_G3_CPU0_G1_TX_DN<6>")
		)
		(pad "U31" smd circle
			(at -5.96011 -23.850092 180)
			(size 0.450088 0.450088)
			(layers "F.Cu" "F.Mask" "F.Paste")
			(net "GND")
		)
		(pad "U32" smd circle
			(at -5.020056 -23.850092 180)
			(size 0.450088 0.450088)
			(layers "F.Cu" "F.Mask" "F.Paste")
			(net "GMI_CPU1_G3_CPU0_G1_TX_DP<3>")
		)
		(pad "U33" smd circle
			(at -4.080002 -23.850092 180)
			(size 0.450088 0.450088)
			(layers "F.Cu" "F.Mask" "F.Paste")
			(net "GMI_CPU1_G3_CPU0_G1_TX_DN<3>")
		)
		(pad "U34" smd circle
			(at -3.139948 -23.850092 180)
			(size 0.450088 0.450088)
			(layers "F.Cu" "F.Mask" "F.Paste")
			(net "GND")
		)
		(pad "U35" smd circle
			(at -2.199894 -23.850092 180)
			(size 0.450088 0.450088)
			(layers "F.Cu" "F.Mask" "F.Paste")
			(net "PVDDCR_CPU0_P1")
		)
		(pad "U36" smd circle
			(at -1.260094 -23.850092 180)
			(size 0.450088 0.450088)
			(layers "F.Cu" "F.Mask" "F.Paste")
			(net "PVDDCR_CPU0_P1")
		)
		(pad "U40" smd circle
			(at 1.560068 -23.850092 180)
			(size 0.450088 0.450088)
			(layers "F.Cu" "F.Mask" "F.Paste")
			(net "PVDDCR_CPU0_P1")
		)
		(pad "U41" smd circle
			(at 2.500122 -23.850092 180)
			(size 0.450088 0.450088)
			(layers "F.Cu" "F.Mask" "F.Paste")
			(net "PVDDCR_CPU0_P1")
		)
		(pad "U42" smd circle
			(at 3.439922 -23.850092 180)
			(size 0.450088 0.450088)
			(layers "F.Cu" "F.Mask" "F.Paste")
			(net "GND")
		)
		(pad "U43" smd circle
			(at 4.379976 -23.850092 180)
			(size 0.450088 0.450088)
			(layers "F.Cu" "F.Mask" "F.Paste")
			(net "P5E_CPU1_G1_RX_DN<3>")
		)
		(pad "U44" smd circle
			(at 5.32003 -23.850092 180)
			(size 0.450088 0.450088)
			(layers "F.Cu" "F.Mask" "F.Paste")
			(net "P5E_CPU1_G1_RX_DP<3>")
		)
		(pad "U45" smd circle
			(at 6.260084 -23.850092 180)
			(size 0.450088 0.450088)
			(layers "F.Cu" "F.Mask" "F.Paste")
			(net "GND")
		)
		(pad "U46" smd circle
			(at 7.199884 -23.850092 180)
			(size 0.450088 0.450088)
			(layers "F.Cu" "F.Mask" "F.Paste")
			(net "P5E_CPU1_G1_RX_DN<6>")
		)
		(pad "U47" smd circle
			(at 8.139938 -23.850092 180)
			(size 0.450088 0.450088)
			(layers "F.Cu" "F.Mask" "F.Paste")
			(net "P5E_CPU1_G1_RX_DP<6>")
		)
		(pad "U48" smd circle
			(at 9.079992 -23.850092 180)
			(size 0.450088 0.450088)
			(layers "F.Cu" "F.Mask" "F.Paste")
			(net "GND")
		)
		(pad "U49" smd circle
			(at 10.020046 -23.850092 180)
			(size 0.450088 0.450088)
			(layers "F.Cu" "F.Mask" "F.Paste")
			(net "P5E_CPU1_G1_RX_DN<12>")
		)
		(pad "U50" smd circle
			(at 10.9601 -23.850092 180)
			(size 0.450088 0.450088)
			(layers "F.Cu" "F.Mask" "F.Paste")
			(net "P5E_CPU1_G1_RX_DP<12>")
		)
		(pad "U51" smd circle
			(at 11.8999 -23.850092 180)
			(size 0.450088 0.450088)
			(layers "F.Cu" "F.Mask" "F.Paste")
			(net "GND")
		)
		(pad "U52" smd circle
			(at 12.839954 -23.850092 180)
			(size 0.450088 0.450088)
			(layers "F.Cu" "F.Mask" "F.Paste")
			(net "P5E_CPU1_G1_RX_DN<15>")
		)
		(pad "U53" smd circle
			(at 13.780008 -23.850092 180)
			(size 0.450088 0.450088)
			(layers "F.Cu" "F.Mask" "F.Paste")
			(net "P5E_CPU1_G1_RX_DP<15>")
		)
		(pad "U54" smd circle
			(at 14.720062 -23.850092 180)
			(size 0.450088 0.450088)
			(layers "F.Cu" "F.Mask" "F.Paste")
			(net "GND")
		)
		(pad "U55" smd circle
			(at 15.660116 -23.850092 180)
			(size 0.450088 0.450088)
			(layers "F.Cu" "F.Mask" "F.Paste")
			(net "M_C_CPU1_SA_DQ<15>")
		)
		(pad "U56" smd circle
			(at 16.599916 -23.850092 180)
			(size 0.450088 0.450088)
			(layers "F.Cu" "F.Mask" "F.Paste")
			(net "GND")
		)
		(pad "U57" smd circle
			(at 17.53997 -23.850092 180)
			(size 0.450088 0.450088)
			(layers "F.Cu" "F.Mask" "F.Paste")
			(net "M_C_CPU1_SA_DQ<16>")
		)
		(pad "U58" smd circle
			(at 18.480024 -23.850092 180)
			(size 0.450088 0.450088)
			(layers "F.Cu" "F.Mask" "F.Paste")
			(net "PVDDIO_P1")
		)
		(pad "U59" smd circle
			(at 19.420078 -23.850092 180)
			(size 0.450088 0.450088)
			(layers "F.Cu" "F.Mask" "F.Paste")
			(net "M_D_CPU1_SA_DQ<15>")
		)
		(pad "U60" smd circle
			(at 20.359878 -23.850092 180)
			(size 0.450088 0.450088)
			(layers "F.Cu" "F.Mask" "F.Paste")
			(net "M_D_CPU1_SA_DQ<16>")
		)
		(pad "U61" smd circle
			(at 21.299932 -23.850092 180)
			(size 0.450088 0.450088)
			(layers "F.Cu" "F.Mask" "F.Paste")
			(net "GND")
		)
		(pad "U62" smd circle
			(at 22.239986 -23.850092 180)
			(size 0.450088 0.450088)
			(layers "F.Cu" "F.Mask" "F.Paste")
			(net "M_B_CPU1_SA_DQ<15>")
		)
		(pad "U63" smd circle
			(at 23.18004 -23.850092 180)
			(size 0.450088 0.450088)
			(layers "F.Cu" "F.Mask" "F.Paste")
			(net "GND")
		)
		(pad "U64" smd circle
			(at 24.120094 -23.850092 180)
			(size 0.450088 0.450088)
			(layers "F.Cu" "F.Mask" "F.Paste")
			(net "M_B_CPU1_SA_DQ<16>")
		)
		(pad "U65" smd circle
			(at 25.059894 -23.850092 180)
			(size 0.450088 0.450088)
			(layers "F.Cu" "F.Mask" "F.Paste")
			(net "PVDDIO_P1")
		)
		(pad "U66" smd circle
			(at 25.999948 -23.850092 180)
			(size 0.450088 0.450088)
			(layers "F.Cu" "F.Mask" "F.Paste")
			(net "M_F_CPU1_SA_DQ<15>")
		)
		(pad "U67" smd circle
			(at 26.940002 -23.850092 180)
			(size 0.450088 0.450088)
			(layers "F.Cu" "F.Mask" "F.Paste")
			(net "M_F_CPU1_SA_DQ<16>")
		)
		(pad "U68" smd circle
			(at 27.880056 -23.850092 180)
			(size 0.450088 0.450088)
			(layers "F.Cu" "F.Mask" "F.Paste")
			(net "GND")
		)
		(pad "U69" smd circle
			(at 28.82011 -23.850092 180)
			(size 0.450088 0.450088)
			(layers "F.Cu" "F.Mask" "F.Paste")
			(net "M_E_CPU1_SA_DQ<15>")
		)
		(pad "U70" smd circle
			(at 29.75991 -23.850092 180)
			(size 0.450088 0.450088)
			(layers "F.Cu" "F.Mask" "F.Paste")
			(net "GND")
		)
		(pad "U71" smd circle
			(at 30.699964 -23.850092 180)
			(size 0.450088 0.450088)
			(layers "F.Cu" "F.Mask" "F.Paste")
			(net "M_E_CPU1_SA_DQ<16>")
		)
		(pad "U72" smd circle
			(at 31.640018 -23.850092 180)
			(size 0.450088 0.450088)
			(layers "F.Cu" "F.Mask" "F.Paste")
			(net "PVDDIO_P1")
		)
		(pad "U73" smd circle
			(at 32.580072 -23.850092 180)
			(size 0.450088 0.450088)
			(layers "F.Cu" "F.Mask" "F.Paste")
			(net "M_A_CPU1_SA_DQ<15>")
		)
		(pad "U74" smd circle
			(at 33.519872 -23.850092 180)
			(size 0.450088 0.450088)
			(layers "F.Cu" "F.Mask" "F.Paste")
			(net "M_A_CPU1_SA_DQ<16>")
		)
		(pad "U75" smd circle
			(at 34.459926 -23.850092 180)
			(size 0.450088 0.450088)
			(layers "F.Cu" "F.Mask" "F.Paste")
			(net "GND")
		)
		(pad "V2" smd circle
			(at -33.690052 -23.040086 180)
			(size 0.450088 0.450088)
			(layers "F.Cu" "F.Mask" "F.Paste")
			(net "M_G_CPU1_SA_DQ<18>")
		)
		(pad "V3" smd circle
			(at -32.749998 -23.040086 180)
			(size 0.450088 0.450088)
			(layers "F.Cu" "F.Mask" "F.Paste")
			(net "GND")
		)
	)
)
